# BASEBOARD_FAB2 (Tioga Pass) — schematic netlist excerpt (pin names and nets, part order shuffled) for the footprints in the layout excerpt that follows; sources: Cadence DE-HDL packaged netlist, KiCad conversion of Wiwynn_Tioga_Pass_MB.brd

EU4E2  IR354XX  IR35412 IC  pkg SM  page 214
  VOS  = PVCCIO_CPU1
  LGND  = GND
  VCC  = VR_PVCCIO_CPU1_PH1_VCIN
  VDRV  = P5V_STBY
  PGND(0)  = GND
  GL(0)  = TP_PVCCIO_CPU1_GL_0
  PGND(1)  = GND
  SW  = VR_PVCCIO_CPU1_PH1_SW
  VIN(0)  = VR_FET_SW_P12V_STBY_PVCCIN_CPU0
  VIN(1)  = VR_FET_SW_P12V_STBY_PVCCIN_CPU0
  NC  = NC
  PHASE  = VR_PVCCIO_CPU1_PH1_PHASE
  BOOST  = VR_PVCCIO_CPU1_PH1_BOOT_R
  PWM  = VR_PVCCIO_CPU1_PWM1
  EN  = P5V_STBY
  TOUT_FLT  = A_TSENSE_PVCCIO_CPU1
  OCSET  = VR_PVCCIO_CPU1_OCSET
  IOUT  = ISENSE_PVCCIO_CPU1_PH1_IMON
  REFIN  = VR_PVCCIO_CPU1_AIREF1
  PGND(2)  = GND
  GL(1)  = TP_PVCCIO_CPU1_GL_1

(kicad_pcb
	(version 20260206)
	(generator "pcbnew")
	(generator_version "10.0")
	(general
		(thickness 1.6)
		(legacy_teardrops no)
	)
	(paper "A4")
	(title_block
		(title "Wiwynn_Tioga_Pass_MB.brd")
		(comment 1 "Tioga Pass / footprints 1078-1078 of 4770")
	)
	(layers
		(0 "F.Cu" signal "TOP")
		(4 "In1.Cu" signal "L2GND")
		(6 "In2.Cu" signal "L3")
		(8 "In3.Cu" signal "L4GND")
		(10 "In4.Cu" signal "L5")
		(12 "In5.Cu" signal "L6GND")
		(14 "In6.Cu" signal "L7VCC")
		(16 "In7.Cu" signal "L8VCC")
		(18 "In8.Cu" signal "L9GND")
		(20 "In9.Cu" signal "L10")
		(22 "In10.Cu" signal "L11GND")
		(24 "In11.Cu" signal "L12")
		(26 "In12.Cu" signal "L13GND")
		(2 "B.Cu" signal "BOTTOM")
		(9 "F.Adhes" user "F.Adhesive")
		(11 "B.Adhes" user "B.Adhesive")
		(13 "F.Paste" user "Package Geometry/Pastemask Top")
		(15 "B.Paste" user "Package Geometry/Pastemask Bottom")
		(5 "F.SilkS" user "Ref Des/Silkscreen Top")
		(7 "B.SilkS" user "Ref Des/Silkscreen Bottom")
		(1 "F.Mask" user "Board Geometry/Soldermask Top")
		(3 "B.Mask" user "Board Geometry/Soldermask Bottom")
		(17 "Dwgs.User" user "User.Drawings")
		(19 "Cmts.User" user "User.Comments")
		(21 "Eco1.User" user "User.Eco1")
		(23 "Eco2.User" user "User.Eco2")
		(25 "Edge.Cuts" user "Board Geometry/Outline")
		(27 "Margin" user)
		(31 "F.CrtYd" user "Package Geometry/Place Bound Top")
		(29 "B.CrtYd" user "Package Geometry/Place Bound Bottom")
		(35 "F.Fab" user "Ref Des/Assembly Top")
		(33 "B.Fab" user "Ref Des/Assembly Bottom")
	)
	(footprint ""
		(layer "F.Cu")
		(at 177.434494 -54.347618 -90)
		(property "Reference" "EU4E2"
			(at 3.320288 0.142494 0)
			(unlocked yes)
			(layer "F.SilkS")
			(effects
				(font
					(size 0.7874 0.5842)
					(thickness 0.1524)
				)
			)
		)
		(property "Value" ""
			(at 0 0 270)
			(layer "F.Fab")
			(effects
				(font
					(size 1.27 1.27)
				)
			)
		)
		(duplicate_pad_numbers_are_jumpers no)
		(fp_line
			(start -3.0099 3.429)
			(end -3.0099 -3.5052)
			(stroke
				(width 0.1524)
				(type default)
			)
			(layer "F.SilkS")
		)
		(fp_line
			(start 2.9718 3.429)
			(end -3.0099 3.429)
			(stroke
				(width 0.1524)
				(type default)
			)
			(layer "F.SilkS")
		)
		(fp_line
			(start -3.0099 -3.5052)
			(end 2.9718 -3.5052)
			(stroke
				(width 0.1524)
				(type default)
			)
			(layer "F.SilkS")
		)
		(fp_line
			(start 2.9718 -3.5052)
			(end 2.9718 3.429)
			(stroke
				(width 0.1524)
				(type default)
			)
			(layer "F.SilkS")
		)
		(fp_circle
			(center -3.057398 -2.678684)
			(end -3.057398 -2.805684)
			(stroke
				(width 0.254)
				(type default)
			)
			(fill no)
			(layer "F.SilkS")
		)
		(fp_poly
			(pts
				(xy -2.9972 -3.4925) (xy -2.9972 -2.6924) (xy -2.1971 -3.4925)
			)
			(stroke
				(width 0)
				(type default)
			)
			(fill yes)
			(layer "F.SilkS")
		)
		(fp_poly
			(pts
				(xy -2.549906 -3.050032) (xy -2.549906 3.050032) (xy 2.549906 3.050032) (xy 2.549906 -3.050032)
			)
			(stroke
				(width 0)
				(type default)
			)
			(fill no)
			(layer "F.CrtYd")
		)
		(fp_line
			(start -2.549906 3.050032)
			(end -2.549906 -3.050032)
			(stroke
				(width 0.1)
				(type default)
			)
			(layer "F.Fab")
		)
		(fp_line
			(start 2.549906 3.050032)
			(end -2.549906 3.050032)
			(stroke
				(width 0.1)
				(type default)
			)
			(layer "F.Fab")
		)
		(fp_line
			(start -2.549906 -3.050032)
			(end 2.549906 -3.050032)
			(stroke
				(width 0.1)
				(type default)
			)
			(layer "F.Fab")
		)
		(fp_line
			(start 2.549906 -3.050032)
			(end 2.549906 3.050032)
			(stroke
				(width 0.1)
				(type default)
			)
			(layer "F.Fab")
		)
		(fp_circle
			(center -3.057398 -2.678684)
			(end -3.057398 -2.805684)
			(stroke
				(width 0.254)
				(type default)
			)
			(fill no)
			(layer "F.Fab")
		)
		(pad "1" smd rect
			(at -2.39522 -2.279904 270)
			(size 0.7112 0.254)
			(layers "F.Cu" "F.Mask" "F.Paste")
			(net "PVCCIO_CPU1")
		)
		(pad "2" smd rect
			(at -2.39522 -1.83007 270)
			(size 0.7112 0.254)
			(layers "F.Cu" "F.Mask" "F.Paste")
			(net "GND")
		)
		(pad "3" smd rect
			(at -2.39522 -1.379982 270)
			(size 0.7112 0.254)
			(layers "F.Cu" "F.Mask" "F.Paste")
			(net "VR_PVCCIO_CPU1_PH1_VCIN")
		)
		(pad "4" smd rect
			(at -2.39522 -0.929894 270)
			(size 0.7112 0.254)
			(layers "F.Cu" "F.Mask" "F.Paste")
			(net "P5V_STBY")
		)
		(pad "5" smd rect
			(at -2.39522 -0.48006 270)
			(size 0.7112 0.254)
			(layers "F.Cu" "F.Mask" "F.Paste")
			(net "GND")
		)
		(pad "6" smd rect
			(at -2.39522 -0.029972 270)
			(size 0.7112 0.254)
			(layers "F.Cu" "F.Mask" "F.Paste")
			(net "TP_PVCCIO_CPU1_GL_0")
		)
		(pad "7" smd custom
			(at 0.016764 1.145032 270)
			(size 0.53975 0.53975)
			(layers "F.Cu" "F.Mask" "F.Paste")
			(net "GND")
			(options
				(clearance outline)
				(anchor circle)
			)
			(primitives
				(gr_poly
					(pts
						(xy -2.7051 1.0795) (xy -2.7051 -0.3683) (xy -0.9271 -0.3683) (xy -0.9271 -1.0795) (xy 2.7051 -1.0795)
						(xy 2.7051 1.0795)
					)
					(width 0)
					(fill yes)
				)
			)
		)
		(pad "10" smd rect
			(at -0.008382 2.874772 270)
			(size 4.3434 0.6096)
			(layers "F.Cu" "F.Mask" "F.Paste")
			(net "VR_PVCCIO_CPU1_PH1_SW")
		)
		(pad "25" smd rect
			(at 1.548384 -1.283208 270)
			(size 2.3368 2.0066)
			(layers "F.Cu" "F.Mask" "F.Paste")
			(net "VR_FET_SW_P12V_STBY_PVCCIN_CPU0")
		)
		(pad "30" smd rect
			(at 2.050034 -2.895092 270)
			(size 0.254 0.7112)
			(layers "F.Cu" "F.Mask" "F.Paste")
			(net "VR_FET_SW_P12V_STBY_PVCCIN_CPU0")
		)
		(pad "31" smd rect
			(at 1.599946 -2.895092 270)
			(size 0.254 0.7112)
			(layers "F.Cu" "F.Mask" "F.Paste")
			(net "Net_367")
		)
		(pad "32" smd rect
			(at 1.150112 -2.895092 270)
			(size 0.254 0.7112)
			(layers "F.Cu" "F.Mask" "F.Paste")
			(net "VR_PVCCIO_CPU1_PH1_PHASE")
		)
		(pad "33" smd rect
			(at 0.700024 -2.895092 270)
			(size 0.254 0.7112)
			(layers "F.Cu" "F.Mask" "F.Paste")
			(net "VR_PVCCIO_CPU1_PH1_BOOT_R")
		)
		(pad "34" smd rect
			(at 0.249936 -2.895092 270)
			(size 0.254 0.7112)
			(layers "F.Cu" "F.Mask" "F.Paste")
			(net "VR_PVCCIO_CPU1_PWM1")
		)
		(pad "35" smd rect
			(at -0.199898 -2.895092 270)
			(size 0.254 0.7112)
			(layers "F.Cu" "F.Mask" "F.Paste")
			(net "P5V_STBY")
		)
		(pad "36" smd rect
			(at -0.649986 -2.895092 270)
			(size 0.254 0.7112)
			(layers "F.Cu" "F.Mask" "F.Paste")
			(net "A_TSENSE_PVCCIO_CPU1")
		)
		(pad "37" smd rect
			(at -1.100074 -2.895092 270)
			(size 0.254 0.7112)
			(layers "F.Cu" "F.Mask" "F.Paste")
			(net "VR_PVCCIO_CPU1_OCSET")
		)
		(pad "38" smd rect
			(at -1.549908 -2.895092 270)
			(size 0.254 0.7112)
			(layers "F.Cu" "F.Mask" "F.Paste")
			(net "ISENSE_PVCCIO_CPU1_PH1_IMON")
		)
		(pad "39" smd rect
			(at -1.999996 -2.895092 270)
			(size 0.254 0.7112)
			(layers "F.Cu" "F.Mask" "F.Paste")
			(net "VR_PVCCIO_CPU1_AIREF1")
		)
		(pad "40" smd rect
			(at -0.871728 -1.283208 270)
			(size 1.8034 2.0066)
			(layers "F.Cu" "F.Mask" "F.Paste")
			(net "GND")
		)
		(pad "41" smd rect
			(at -1.533906 0.247904 270)
			(size 0.508 0.3556)
			(layers "F.Cu" "F.Mask" "F.Paste")
			(net "TP_PVCCIO_CPU1_GL_1")
		)
	)
)
